# T6G (Grand Teton) — schematic netlist excerpt (pin names and nets, part order shuffled) for the footprints in the layout excerpt that follows; sources: Cadence DE-HDL packaged netlist, KiCad conversion of 04192023_DAF0TMB3IC0_F0TG_MB_C_brd_V02_OCP.brd

PL21  Q_INDUCTOR4P_14  150NH IND  pkg L_TLM117513Q-151QL_11X7-5XA  page 206
  \1\  = SW_PVDDIO_P0_SW3
  \2\  = IND_PVDDIO_P0_CPL4
  \3\  = IND_PVDDIO_P0_CPL3
  \4\  = PVDDIO_P0

PR6005  Q_RES  60.4K 1% CHIP  pkg 0402LF  page 270 : A = GND ; B = P1V2_AUX_MODE

(kicad_pcb
	(version 20260206)
	(generator "pcbnew")
	(generator_version "10.0")
	(general
		(thickness 1.6)
		(legacy_teardrops no)
	)
	(paper "A4")
	(title_block
		(title "04192023_DAF0TMB3IC0_F0TG_MB_C_brd_V02_OCP.brd")
		(comment 1 "Grand Teton / footprints 4609-4610 of 8354")
	)
	(layers
		(0 "F.Cu" signal "TOP")
		(4 "In1.Cu" signal "GND")
		(6 "In2.Cu" signal "IN1")
		(8 "In3.Cu" signal "GND1")
		(10 "In4.Cu" signal "IN2")
		(12 "In5.Cu" signal "GND2")
		(14 "In6.Cu" signal "IN3")
		(16 "In7.Cu" signal "GND3")
		(18 "In8.Cu" signal "VCC")
		(20 "In9.Cu" signal "VCC1")
		(22 "In10.Cu" signal "GND4")
		(24 "In11.Cu" signal "IN4")
		(26 "In12.Cu" signal "GND5")
		(28 "In13.Cu" signal "IN5")
		(30 "In14.Cu" signal "GND6")
		(32 "In15.Cu" signal "IN6")
		(34 "In16.Cu" signal "GND7")
		(2 "B.Cu" signal "BOTTOM")
		(9 "F.Adhes" user "F.Adhesive")
		(11 "B.Adhes" user "B.Adhesive")
		(13 "F.Paste" user "Package Geometry/Pastemask Top")
		(15 "B.Paste" user "Package Geometry/Pastemask Bottom")
		(5 "F.SilkS" user "Ref Des/Silkscreen Top")
		(7 "B.SilkS" user "Ref Des/Silkscreen Bottom")
		(1 "F.Mask" user "Board Geometry/Soldermask Top")
		(3 "B.Mask" user "Board Geometry/Soldermask Bottom")
		(17 "Dwgs.User" user "User.Drawings")
		(19 "Cmts.User" user "User.Comments")
		(21 "Eco1.User" user "User.Eco1")
		(23 "Eco2.User" user "User.Eco2")
		(25 "Edge.Cuts" user "Board Geometry/Outline")
		(27 "Margin" user)
		(31 "F.CrtYd" user "Package Geometry/Place Bound Top")
		(29 "B.CrtYd" user "Package Geometry/Place Bound Bottom")
		(35 "F.Fab" user "Ref Des/Assembly Top")
		(33 "B.Fab" user "Ref Des/Assembly Bottom")
	)
	(footprint ""
		(layer "F.Cu")
		(at 122.952002 -78.732888 -90)
		(property "Reference" "PR6005"
			(at 0 0 270)
			(layer "F.SilkS")
			(hide yes)
			(effects
				(font
					(size 1.27 1.27)
				)
			)
		)
		(property "Value" ""
			(at 0 0 270)
			(layer "F.Fab")
			(effects
				(font
					(size 1.27 1.27)
				)
			)
		)
		(duplicate_pad_numbers_are_jumpers no)
		(fp_line
			(start -0.7874 0.4064)
			(end -0.7874 -0.4064)
			(stroke
				(width 0.1524)
				(type default)
			)
			(layer "F.SilkS")
		)
		(fp_line
			(start 0.7874 0.4064)
			(end -0.7874 0.4064)
			(stroke
				(width 0.1524)
				(type default)
			)
			(layer "F.SilkS")
		)
		(fp_line
			(start -0.7874 -0.4064)
			(end 0.7874 -0.4064)
			(stroke
				(width 0.1524)
				(type default)
			)
			(layer "F.SilkS")
		)
		(fp_line
			(start 0.7874 -0.4064)
			(end 0.7874 0.4064)
			(stroke
				(width 0.1524)
				(type default)
			)
			(layer "F.SilkS")
		)
		(fp_line
			(start -0.67945 0.3048)
			(end -0.67945 -0.305054)
			(stroke
				(width 0.1)
				(type default)
			)
			(layer "F.Fab")
		)
		(fp_line
			(start -0.12065 0.3048)
			(end -0.67945 0.3048)
			(stroke
				(width 0.1)
				(type default)
			)
			(layer "F.Fab")
		)
		(fp_line
			(start 0.120396 0.3048)
			(end 0.120396 0.2794)
			(stroke
				(width 0.1)
				(type default)
			)
			(layer "F.Fab")
		)
		(fp_line
			(start 0.67945 0.3048)
			(end 0.120396 0.3048)
			(stroke
				(width 0.1)
				(type default)
			)
			(layer "F.Fab")
		)
		(fp_line
			(start -0.12065 0.2794)
			(end -0.12065 0.3048)
			(stroke
				(width 0.1)
				(type default)
			)
			(layer "F.Fab")
		)
		(fp_line
			(start 0.120396 0.2794)
			(end -0.12065 0.2794)
			(stroke
				(width 0.1)
				(type default)
			)
			(layer "F.Fab")
		)
		(fp_line
			(start -0.12065 -0.2794)
			(end 0.12065 -0.2794)
			(stroke
				(width 0.1)
				(type default)
			)
			(layer "F.Fab")
		)
		(fp_line
			(start 0.12065 -0.2794)
			(end 0.12065 -0.3048)
			(stroke
				(width 0.1)
				(type default)
			)
			(layer "F.Fab")
		)
		(fp_line
			(start 0.12065 -0.3048)
			(end 0.67945 -0.3048)
			(stroke
				(width 0.1)
				(type default)
			)
			(layer "F.Fab")
		)
		(fp_line
			(start 0.67945 -0.3048)
			(end 0.67945 0.3048)
			(stroke
				(width 0.1)
				(type default)
			)
			(layer "F.Fab")
		)
		(fp_line
			(start -0.67945 -0.305054)
			(end -0.12065 -0.305054)
			(stroke
				(width 0.1)
				(type default)
			)
			(layer "F.Fab")
		)
		(fp_line
			(start -0.12065 -0.305054)
			(end -0.12065 -0.2794)
			(stroke
				(width 0.1)
				(type default)
			)
			(layer "F.Fab")
		)
		(pad "1" smd circle
			(at -0.40005 0 270)
			(size 0 0)
			(layers "F.Cu" "F.Mask" "F.Paste")
			(net "GND")
		)
		(pad "2" smd circle
			(at 0.40005 0 270)
			(size 0 0)
			(layers "F.Cu" "F.Mask" "F.Paste")
			(net "P1V2_AUX_MODE")
		)
	)
	(footprint ""
		(layer "F.Cu")
		(at 283.820362 -337.399122)
		(property "Reference" "PL21"
			(at -2.607056 -16.014446 0)
			(unlocked yes)
			(layer "F.SilkS")
			(effects
				(font
					(size 0.7874 0.5842)
					(thickness 0.1524)
				)
				(justify left)
			)
		)
		(property "Value" ""
			(at 0 0 0)
			(layer "F.Fab")
			(effects
				(font
					(size 1.27 1.27)
				)
			)
		)
		(duplicate_pad_numbers_are_jumpers no)
		(fp_line
			(start -3.750056 -5.500116)
			(end -2.393442 -5.500116)
			(stroke
				(width 0.1524)
				(type default)
			)
			(layer "F.SilkS")
		)
		(fp_line
			(start -3.750056 5.500116)
			(end -3.750056 -5.500116)
			(stroke
				(width 0.1524)
				(type default)
			)
			(layer "F.SilkS")
		)
		(fp_line
			(start -2.393442 5.500116)
			(end -3.750056 5.500116)
			(stroke
				(width 0.1524)
				(type default)
			)
			(layer "F.SilkS")
		)
		(fp_line
			(start 2.393442 5.500116)
			(end 3.750056 5.500116)
			(stroke
				(width 0.1524)
				(type default)
			)
			(layer "F.SilkS")
		)
		(fp_line
			(start 3.750056 -5.500116)
			(end 2.393442 -5.500116)
			(stroke
				(width 0.1524)
				(type default)
			)
			(layer "F.SilkS")
		)
		(fp_line
			(start 3.750056 5.500116)
			(end 3.750056 -5.500116)
			(stroke
				(width 0.1524)
				(type default)
			)
			(layer "F.SilkS")
		)
		(fp_poly
			(pts
				(xy -3.9116 -4.249928) (xy -4.3434 -4.034028) (xy -4.3434 -4.465828)
			)
			(stroke
				(width 0)
				(type default)
			)
			(fill yes)
			(layer "F.SilkS")
		)
		(fp_line
			(start -3.750056 -5.500116)
			(end -3.750056 5.500116)
			(stroke
				(width 0.1)
				(type default)
			)
			(layer "F.Fab")
		)
		(fp_line
			(start -3.750056 5.500116)
			(end 3.750056 5.500116)
			(stroke
				(width 0.1)
				(type default)
			)
			(layer "F.Fab")
		)
		(fp_line
			(start 3.750056 -5.500116)
			(end -3.750056 -5.500116)
			(stroke
				(width 0.1)
				(type default)
			)
			(layer "F.Fab")
		)
		(fp_line
			(start 3.750056 5.500116)
			(end 3.750056 -5.500116)
			(stroke
				(width 0.1)
				(type default)
			)
			(layer "F.Fab")
		)
		(fp_poly
			(pts
				(xy -4.9276 -4.757928) (xy -4.9276 -3.741928) (xy -3.9116 -4.249928)
			)
			(stroke
				(width 0)
				(type default)
			)
			(fill yes)
			(layer "F.Fab")
		)
		(pad "1" smd rect
			(at 0 -4.249928 270)
			(size 2.413 4.5212)
			(layers "F.Cu" "F.Mask" "F.Paste")
			(net "SW_PVDDIO_P0_SW3")
		)
		(pad "2" smd rect
			(at 0 -1.175004 270)
			(size 1.3716 4.5212)
			(layers "F.Cu" "F.Mask" "F.Paste")
			(net "IND_PVDDIO_P0_CPL4")
		)
		(pad "3" smd rect
			(at 0 1.175004 270)
			(size 1.3716 4.5212)
			(layers "F.Cu" "F.Mask" "F.Paste")
			(net "IND_PVDDIO_P0_CPL3")
		)
		(pad "4" smd rect
			(at 0 4.249928 270)
			(size 2.413 4.5212)
			(layers "F.Cu" "F.Mask" "F.Paste")
			(net "PVDDIO_P0")
		)
	)
)
